(kicad_pcb
	(version 20241229)
	(generator "pcbnew")
	(generator_version "9.0")
	(general
		(thickness 1.6642)
		(legacy_teardrops no)
	)
	(paper "A3")
	(title_block
		(title "PolarFire SoM")
		(date "2025-07-22")
		(rev "1.1.4")
		(company "Antmicro Ltd")
		(comment 1 "www.antmicro.com")
		(comment 9 "footprints 13-17 of 470")
	)
	(layers
		(0 "F.Cu" mixed)
		(4 "In1.Cu" power)
		(6 "In2.Cu" signal)
		(8 "In3.Cu" power)
		(10 "In4.Cu" signal)
		(12 "In5.Cu" power)
		(14 "In6.Cu" power)
		(16 "In7.Cu" signal)
		(18 "In8.Cu" power)
		(20 "In9.Cu" signal)
		(22 "In10.Cu" power)
		(24 "In11.Cu" signal)
		(26 "In12.Cu" signal)
		(2 "B.Cu" mixed)
		(9 "F.Adhes" user "F.Adhesive")
		(11 "B.Adhes" user "B.Adhesive")
		(13 "F.Paste" user)
		(15 "B.Paste" user)
		(5 "F.SilkS" user "F.Silkscreen")
		(7 "B.SilkS" user "B.Silkscreen")
		(1 "F.Mask" user)
		(3 "B.Mask" user)
		(17 "Dwgs.User" user "User.Drawings")
		(19 "Cmts.User" user "User.Comments")
		(21 "Eco1.User" user "User.Eco1")
		(23 "Eco2.User" user "User.Eco2")
		(25 "Edge.Cuts" user)
		(27 "Margin" user)
		(31 "F.CrtYd" user "F.Courtyard")
		(29 "B.CrtYd" user "B.Courtyard")
		(35 "F.Fab" user)
		(33 "B.Fab" user)
	)
	(footprint "antmicro-footprints:C_0402_1005Metric"
		(layer "F.Cu")
		(at 208.07 151.68 180)
		(descr "Capacitor SMD 0402")
		(tags "capacitor SMD 0402")
		(property "Reference" "C211"
			(at -1.76 -2.47 180)
			(layer "F.SilkS")
			(effects
				(font
					(size 0.7 0.7)
					(thickness 0.15)
				)
				(justify right bottom)
			)
		)
		(property "Value" "C_100n_0402"
			(at -1.022927 2.155213 0)
			(layer "F.Fab")
			(hide yes)
			(effects
				(font
					(size 0.7 0.7)
					(thickness 0.15)
				)
				(justify right bottom)
			)
		)
		(property "Datasheet" "https://www.murata.com/products/productdetail?partno=GRM155R61H104KE14%23"
			(at 0 0 180)
			(layer "F.Fab")
			(hide yes)
			(effects
				(font
					(size 1.27 1.27)
					(thickness 0.15)
				)
			)
		)
		(property "Description" "SMD Multilayer Ceramic Capacitor, 0.1 µF, 50 V, 0402 [1005 Metric], ± 10%, X5R, GRM Series"
			(at 0 0 180)
			(layer "F.Fab")
			(hide yes)
			(effects
				(font
					(size 1.27 1.27)
					(thickness 0.15)
				)
			)
		)
		(property "Author" "Antmicro"
			(at 416.14 303.36 0)
			(layer "F.Fab")
			(hide yes)
			(effects
				(font
					(size 1 1)
					(thickness 0.15)
				)
			)
		)
		(property "Dielectric" "X5R"
			(at 416.14 303.36 0)
			(layer "F.Fab")
			(hide yes)
			(effects
				(font
					(size 1 1)
					(thickness 0.15)
				)
			)
		)
		(property "License" "Apache-2.0"
			(at 416.14 303.36 0)
			(layer "F.Fab")
			(hide yes)
			(effects
				(font
					(size 1 1)
					(thickness 0.15)
				)
			)
		)
		(property "MPN" "GRM155R61H104KE14D"
			(at 416.14 303.36 0)
			(layer "F.Fab")
			(hide yes)
			(effects
				(font
					(size 1 1)
					(thickness 0.15)
				)
			)
		)
		(property "Manufacturer" "Murata"
			(at 416.14 303.36 0)
			(layer "F.Fab")
			(hide yes)
			(effects
				(font
					(size 1 1)
					(thickness 0.15)
				)
			)
		)
		(property "Public" ""
			(at 416.14 303.36 0)
			(layer "F.Fab")
			(hide yes)
			(effects
				(font
					(size 1 1)
					(thickness 0.15)
				)
			)
		)
		(property "Val" "100n"
			(at 416.14 303.36 0)
			(layer "F.Fab")
			(hide yes)
			(effects
				(font
					(size 1 1)
					(thickness 0.15)
				)
			)
		)
		(property "Voltage" "50V"
			(at 416.14 303.36 0)
			(layer "F.Fab")
			(hide yes)
			(effects
				(font
					(size 1 1)
					(thickness 0.15)
				)
			)
		)
		(sheetname "/MIPI CrossLink/")
		(sheetfile "crosslink.kicad_sch")
		(attr smd)
		(fp_rect
			(start -0.925 -0.47)
			(end 0.925 0.47)
			(stroke
				(width 0.05)
				(type default)
			)
			(fill no)
			(layer "F.CrtYd")
		)
		(fp_line
			(start 0.504 0.248)
			(end -0.494 0.248)
			(stroke
				(width 0.15)
				(type solid)
			)
			(layer "F.Fab")
		)
		(fp_line
			(start 0.504 -0.25)
			(end 0.504 0.248)
			(stroke
				(width 0.15)
				(type solid)
			)
			(layer "F.Fab")
		)
		(fp_line
			(start -0.494 0.248)
			(end -0.494 -0.25)
			(stroke
				(width 0.15)
				(type solid)
			)
			(layer "F.Fab")
		)
		(fp_line
			(start -0.494 -0.25)
			(end 0.504 -0.25)
			(stroke
				(width 0.15)
				(type solid)
			)
			(layer "F.Fab")
		)
		(fp_text user "Author: Antmicro"
			(at -0.939 3.399 180)
			(layer "F.Fab")
			(effects
				(font
					(size 0.7 0.7)
					(thickness 0.15)
				)
				(justify left bottom)
			)
		)
		(fp_text user "${REFERENCE}"
			(at -0.939 4.599 180)
			(layer "F.Fab")
			(effects
				(font
					(size 0.7 0.7)
					(thickness 0.15)
				)
				(justify left bottom)
			)
		)
		(fp_text user "License: Apache-2.0"
			(at -0.939 5.799 180)
			(layer "F.Fab")
			(effects
				(font
					(size 0.7 0.7)
					(thickness 0.15)
				)
				(justify left bottom)
			)
		)
		(pad "1" smd roundrect
			(at -0.48 0 180)
			(size 0.59 0.64)
			(layers "F.Cu" "F.Mask" "F.Paste")
			(roundrect_rratio 0.25)
			(net 417 "GND")
			(pintype "passive")
		)
		(pad "2" smd roundrect
			(at 0.48 0 180)
			(size 0.59 0.64)
			(layers "F.Cu" "F.Mask" "F.Paste")
			(roundrect_rratio 0.25)
			(net 203 "/MIPI CrossLink/CL_VCCA_DPHY0")
			(pintype "passive")
		)
	)
	(footprint "antmicro-footprints:R_Array_4x0201_Panasonic_EXB18V"
		(layer "F.Cu")
		(at 205.593002 121.25 -90)
		(property "Reference" "R25"
			(at 1.75 1.193002 180)
			(layer "F.SilkS")
			(effects
				(font
					(size 0.7 0.7)
					(thickness 0.15)
				)
				(justify left bottom)
			)
		)
		(property "Value" "R_4x0R_0201_array"
			(at -1.1 1.8 90)
			(layer "F.Fab")
			(hide yes)
			(effects
				(font
					(size 0.7 0.7)
					(thickness 0.15)
				)
				(justify right bottom)
			)
		)
		(property "Datasheet" "http://industrial.panasonic.com/cdbs/www-data/pdf/AOC0000/AOC0000C14.pdf"
			(at 0 0 270)
			(layer "F.Fab")
			(hide yes)
			(effects
				(font
					(size 1.27 1.27)
					(thickness 0.15)
				)
			)
		)
		(property "Description" "Zero Ohm Network Resistor, Jumper, 0201 [0603 Metric], Thick Film, Isolated, Flat, 4 Resistors"
			(at 0 0 270)
			(layer "F.Fab")
			(hide yes)
			(effects
				(font
					(size 1.27 1.27)
					(thickness 0.15)
				)
			)
		)
		(property "Author" "Antmicro"
			(at 84.343002 326.843002 0)
			(layer "F.Fab")
			(hide yes)
			(effects
				(font
					(size 1 1)
					(thickness 0.15)
				)
			)
		)
		(property "DNP" "DNP"
			(at 84.343002 326.843002 0)
			(layer "F.Fab")
			(hide yes)
			(effects
				(font
					(size 1 1)
					(thickness 0.15)
				)
			)
		)
		(property "License" "Apache-2.0"
			(at 84.343002 326.843002 0)
			(layer "F.Fab")
			(hide yes)
			(effects
				(font
					(size 1 1)
					(thickness 0.15)
				)
			)
		)
		(property "MPN" "EXB-18VR000X"
			(at 84.343002 326.843002 0)
			(layer "F.Fab")
			(hide yes)
			(effects
				(font
					(size 1 1)
					(thickness 0.15)
				)
			)
		)
		(property "Manufacturer" "Panasonic"
			(at 84.343002 326.843002 0)
			(layer "F.Fab")
			(hide yes)
			(effects
				(font
					(size 1 1)
					(thickness 0.15)
				)
			)
		)
		(property "Val" "4x0R_0201"
			(at 84.343002 326.843002 0)
			(layer "F.Fab")
			(hide yes)
			(effects
				(font
					(size 1 1)
					(thickness 0.15)
				)
			)
		)
		(sheetname "/FPGA MSSIO/")
		(sheetfile "fpga-mssio.kicad_sch")
		(attr smd dnp)
		(fp_line
			(start -0.8 -0.45)
			(end -0.8 0.45)
			(stroke
				(width 0.12)
				(type solid)
			)
			(layer "F.SilkS")
		)
		(fp_line
			(start 0.8 -0.45)
			(end 0.8 0.45)
			(stroke
				(width 0.12)
				(type solid)
			)
			(layer "F.SilkS")
		)
		(fp_rect
			(start -0.898 -0.66)
			(end 0.898 0.65)
			(stroke
				(width 0.05)
				(type solid)
			)
			(fill no)
			(layer "F.CrtYd")
		)
		(fp_text user "License: Apache-2.0"
			(at -1.051 6 270)
			(layer "F.Fab")
			(effects
				(font
					(size 0.7 0.7)
					(thickness 0.15)
				)
				(justify left bottom)
			)
		)
		(fp_text user "Author: Antmicro"
			(at -1.051 4.599 270)
			(layer "F.Fab")
			(effects
				(font
					(size 0.7 0.7)
					(thickness 0.15)
				)
				(justify left bottom)
			)
		)
		(fp_text user "${REFERENCE}"
			(at -1.051 3.2 270)
			(layer "F.Fab")
			(effects
				(font
					(size 0.7 0.7)
					(thickness 0.15)
				)
				(justify left bottom)
			)
		)
		(pad "1" smd roundrect
			(at -0.6 0.298 270)
			(size 0.2 0.4)
			(layers "F.Cu" "F.Mask" "F.Paste")
			(roundrect_rratio 0.25)
			(net 266 "/FPGA MSSIO/SD.DAT3")
			(pinfunction "R1.1")
			(pintype "passive")
		)
		(pad "2" smd roundrect
			(at -0.202 0.298 270)
			(size 0.2 0.4)
			(layers "F.Cu" "F.Mask" "F.Paste")
			(roundrect_rratio 0.25)
			(net 267 "/FPGA MSSIO/SD.DAT0")
			(pinfunction "R2.1")
			(pintype "passive")
		)
		(pad "3" smd roundrect
			(at 0.2 0.298 270)
			(size 0.2 0.4)
			(layers "F.Cu" "F.Mask" "F.Paste")
			(roundrect_rratio 0.25)
			(net 268 "/FPGA MSSIO/SD.DAT5")
			(pinfunction "R3.1")
			(pintype "passive")
		)
		(pad "4" smd roundrect
			(at 0.598 0.298 270)
			(size 0.2 0.4)
			(layers "F.Cu" "F.Mask" "F.Paste")
			(roundrect_rratio 0.25)
			(net 269 "/FPGA MSSIO/SD.DAT7")
			(pinfunction "R4.1")
			(pintype "passive")
		)
		(pad "5" smd roundrect
			(at 0.598 -0.3 270)
			(size 0.2 0.4)
			(layers "F.Cu" "F.Mask" "F.Paste")
			(roundrect_rratio 0.25)
			(net 215 "/FPGA MSSIO/MEM.DAT7")
			(pinfunction "R4.2")
			(pintype "passive")
		)
		(pad "6" smd roundrect
			(at 0.2 -0.3 270)
			(size 0.2 0.4)
			(layers "F.Cu" "F.Mask" "F.Paste")
			(roundrect_rratio 0.25)
			(net 216 "/FPGA MSSIO/MEM.DAT5")
			(pinfunction "R3.2")
			(pintype "passive")
		)
		(pad "7" smd roundrect
			(at -0.202 -0.3 270)
			(size 0.2 0.4)
			(layers "F.Cu" "F.Mask" "F.Paste")
			(roundrect_rratio 0.25)
			(net 235 "/FPGA MSSIO/MEM.DAT0")
			(pinfunction "R2.2")
			(pintype "passive")
		)
		(pad "8" smd roundrect
			(at -0.6 -0.3 270)
			(size 0.2 0.4)
			(layers "F.Cu" "F.Mask" "F.Paste")
			(roundrect_rratio 0.25)
			(net 236 "/FPGA MSSIO/MEM.DAT3")
			(pinfunction "R1.2")
			(pintype "passive")
		)
	)
	(footprint "antmicro-footprints:TP_SMD_0.75mm"
		(layer "F.Cu")
		(at 217.4 145 90)
		(property "Reference" "TP10"
			(at 0 -0.6 90)
			(layer "F.SilkS")
			(hide yes)
			(effects
				(font
					(size 0.7 0.7)
					(thickness 0.15)
				)
				(justify left bottom)
			)
		)
		(property "Value" "TP_0.75mm_SMD"
			(at 0 1.2 90)
			(layer "F.Fab")
			(hide yes)
			(effects
				(font
					(size 0.7 0.7)
					(thickness 0.15)
				)
				(justify left bottom)
			)
		)
		(property "Description" "SMT test point"
			(at 0 0 90)
			(layer "F.Fab")
			(hide yes)
			(effects
				(font
					(size 1.27 1.27)
					(thickness 0.15)
				)
			)
		)
		(property "Author" "Antmicro"
			(at 362.4 -72.4 0)
			(layer "F.Fab")
			(hide yes)
			(effects
				(font
					(size 1 1)
					(thickness 0.15)
				)
			)
		)
		(property "License" "Apache-2.0"
			(at 362.4 -72.4 0)
			(layer "F.Fab")
			(hide yes)
			(effects
				(font
					(size 1 1)
					(thickness 0.15)
				)
			)
		)
		(property "MPN" ""
			(at 362.4 -72.4 0)
			(layer "F.Fab")
			(hide yes)
			(effects
				(font
					(size 1 1)
					(thickness 0.15)
				)
			)
		)
		(property "Manufacturer" ""
			(at 362.4 -72.4 0)
			(layer "F.Fab")
			(hide yes)
			(effects
				(font
					(size 1 1)
					(thickness 0.15)
				)
			)
		)
		(property "Public" "False"
			(at 362.4 -72.4 0)
			(layer "F.Fab")
			(hide yes)
			(effects
				(font
					(size 1 1)
					(thickness 0.15)
				)
			)
		)
		(sheetname "/USB/")
		(sheetfile "usb.kicad_sch")
		(attr exclude_from_pos_files exclude_from_bom)
		(fp_circle
			(center 0 0)
			(end 0.475 0)
			(stroke
				(width 0.05)
				(type default)
			)
			(fill no)
			(layer "F.CrtYd")
		)
		(fp_text user "${REFERENCE}"
			(at -0.4 2.7 90)
			(layer "F.Fab")
			(effects
				(font
					(size 0.7 0.7)
					(thickness 0.15)
				)
				(justify left bottom)
			)
		)
		(fp_text user "License: Apache-2.0"
			(at -0.4 5.101 90)
			(layer "F.Fab")
			(effects
				(font
					(size 0.7 0.7)
					(thickness 0.15)
				)
				(justify left bottom)
			)
		)
		(fp_text user "Author: Antmicro"
			(at -0.4 3.901 90)
			(layer "F.Fab")
			(effects
				(font
					(size 0.7 0.7)
					(thickness 0.15)
				)
				(justify left bottom)
			)
		)
		(pad "1" smd circle
			(at 0 0 90)
			(size 0.75 0.75)
			(layers "F.Cu" "F.Mask")
			(net 330 "Net-(U13-CPEN)")
			(pinfunction "1")
			(pintype "passive")
		)
	)
	(footprint "antmicro-footprints:C_0402_1005Metric"
		(layer "F.Cu")
		(at 178.5 138.3175 -90)
		(descr "Capacitor SMD 0402")
		(tags "capacitor SMD 0402")
		(property "Reference" "C92"
			(at -4.1175 -8.99 0)
			(layer "F.SilkS")
			(effects
				(font
					(size 0.7 0.7)
					(thickness 0.15)
				)
				(justify right bottom)
			)
		)
		(property "Value" "C_100n_0402"
			(at -1.022927 2.155213 90)
			(layer "F.Fab")
			(hide yes)
			(effects
				(font
					(size 0.7 0.7)
					(thickness 0.15)
				)
				(justify right bottom)
			)
		)
		(property "Datasheet" "https://www.murata.com/products/productdetail?partno=GRM155R61H104KE14%23"
			(at 0 0 270)
			(layer "F.Fab")
			(hide yes)
			(effects
				(font
					(size 1.27 1.27)
					(thickness 0.15)
				)
			)
		)
		(property "Description" "SMD Multilayer Ceramic Capacitor, 0.1 µF, 50 V, 0402 [1005 Metric], ± 10%, X5R, GRM Series"
			(at 0 0 270)
			(layer "F.Fab")
			(hide yes)
			(effects
				(font
					(size 1.27 1.27)
					(thickness 0.15)
				)
			)
		)
		(property "Author" "Antmicro"
			(at 40.1825 316.8175 0)
			(layer "F.Fab")
			(hide yes)
			(effects
				(font
					(size 1 1)
					(thickness 0.15)
				)
			)
		)
		(property "Dielectric" "X5R"
			(at 40.1825 316.8175 0)
			(layer "F.Fab")
			(hide yes)
			(effects
				(font
					(size 1 1)
					(thickness 0.15)
				)
			)
		)
		(property "License" "Apache-2.0"
			(at 40.1825 316.8175 0)
			(layer "F.Fab")
			(hide yes)
			(effects
				(font
					(size 1 1)
					(thickness 0.15)
				)
			)
		)
		(property "MPN" "GRM155R61H104KE14D"
			(at 40.1825 316.8175 0)
			(layer "F.Fab")
			(hide yes)
			(effects
				(font
					(size 1 1)
					(thickness 0.15)
				)
			)
		)
		(property "Manufacturer" "Murata"
			(at 40.1825 316.8175 0)
			(layer "F.Fab")
			(hide yes)
			(effects
				(font
					(size 1 1)
					(thickness 0.15)
				)
			)
		)
		(property "Public" ""
			(at 40.1825 316.8175 0)
			(layer "F.Fab")
			(hide yes)
			(effects
				(font
					(size 1 1)
					(thickness 0.15)
				)
			)
		)
		(property "Val" "100n"
			(at 40.1825 316.8175 0)
			(layer "F.Fab")
			(hide yes)
			(effects
				(font
					(size 1 1)
					(thickness 0.15)
				)
			)
		)
		(property "Voltage" "50V"
			(at 40.1825 316.8175 0)
			(layer "F.Fab")
			(hide yes)
			(effects
				(font
					(size 1 1)
					(thickness 0.15)
				)
			)
		)
		(sheetname "/Supply/")
		(sheetfile "supply.kicad_sch")
		(attr smd)
		(fp_rect
			(start -0.925 -0.47)
			(end 0.925 0.47)
			(stroke
				(width 0.05)
				(type default)
			)
			(fill no)
			(layer "F.CrtYd")
		)
		(fp_line
			(start -0.494 0.248)
			(end -0.494 -0.25)
			(stroke
				(width 0.15)
				(type solid)
			)
			(layer "F.Fab")
		)
		(fp_line
			(start 0.504 0.248)
			(end -0.494 0.248)
			(stroke
				(width 0.15)
				(type solid)
			)
			(layer "F.Fab")
		)
		(fp_line
			(start -0.494 -0.25)
			(end 0.504 -0.25)
			(stroke
				(width 0.15)
				(type solid)
			)
			(layer "F.Fab")
		)
		(fp_line
			(start 0.504 -0.25)
			(end 0.504 0.248)
			(stroke
				(width 0.15)
				(type solid)
			)
			(layer "F.Fab")
		)
		(fp_text user "Author: Antmicro"
			(at -0.939 3.399 270)
			(layer "F.Fab")
			(effects
				(font
					(size 0.7 0.7)
					(thickness 0.15)
				)
				(justify left bottom)
			)
		)
		(fp_text user "${REFERENCE}"
			(at -0.939 4.599 270)
			(layer "F.Fab")
			(effects
				(font
					(size 0.7 0.7)
					(thickness 0.15)
				)
				(justify left bottom)
			)
		)
		(fp_text user "License: Apache-2.0"
			(at -0.939 5.799 270)
			(layer "F.Fab")
			(effects
				(font
					(size 0.7 0.7)
					(thickness 0.15)
				)
				(justify left bottom)
			)
		)
		(pad "1" smd roundrect
			(at -0.48 0 270)
			(size 0.59 0.64)
			(layers "F.Cu" "F.Mask" "F.Paste")
			(roundrect_rratio 0.25)
			(net 417 "GND")
			(pintype "passive")
		)
		(pad "2" smd roundrect
			(at 0.48 0 270)
			(size 0.59 0.64)
			(layers "F.Cu" "F.Mask" "F.Paste")
			(roundrect_rratio 0.25)
			(net 3 "Net-(U7-AVIN)")
			(pintype "passive")
		)
	)
	(footprint "antmicro-footprints:L_0806_2016Metric"
		(layer "F.Cu")
		(at 183.374 144.003695 -90)
		(property "Reference" "L5"
			(at 2.656305 -0.726 180)
			(layer "F.SilkS")
			(effects
				(font
					(size 0.7 0.7)
					(thickness 0.15)
				)
				(justify right bottom)
			)
		)
		(property "Value" "L_1u5_2.8A_0806"
			(at 0 2 90)
			(layer "F.Fab")
			(hide yes)
			(effects
				(font
					(size 0.7 0.7)
					(thickness 0.15)
				)
				(justify right bottom)
			)
		)
		(property "Datasheet" "https://abracon.com/datasheets/AOTA-B201610S.pdf"
			(at 0 0 270)
			(layer "F.Fab")
			(hide yes)
			(effects
				(font
					(size 1.27 1.27)
					(thickness 0.15)
				)
			)
		)
		(property "Description" "Power Inductor (SMT), 1.5 µH, 0.074 ohm, 2.8 A, AOTA-B201610S"
			(at 0 0 270)
			(layer "F.Fab")
			(hide yes)
			(effects
				(font
					(size 1.27 1.27)
					(thickness 0.15)
				)
			)
		)
		(property "Author" "Antmicro"
			(at 39.370305 327.377695 0)
			(layer "F.Fab")
			(hide yes)
			(effects
				(font
					(size 1 1)
					(thickness 0.15)
				)
			)
		)
		(property "IMax" "2.8 A"
			(at 39.370305 327.377695 0)
			(layer "F.Fab")
			(hide yes)
			(effects
				(font
					(size 1 1)
					(thickness 0.15)
				)
			)
		)
		(property "ISat" "3.5 A"
			(at 39.370305 327.377695 0)
			(layer "F.Fab")
			(hide yes)
			(effects
				(font
					(size 1 1)
					(thickness 0.15)
				)
			)
		)
		(property "License" "Apache-2.0"
			(at 39.370305 327.377695 0)
			(layer "F.Fab")
			(hide yes)
			(effects
				(font
					(size 1 1)
					(thickness 0.15)
				)
			)
		)
		(property "MPN" "AOTA-B201610S1R5MT"
			(at 39.370305 327.377695 0)
			(layer "F.Fab")
			(hide yes)
			(effects
				(font
					(size 1 1)
					(thickness 0.15)
				)
			)
		)
		(property "Manufacturer" "Abracon"
			(at 39.370305 327.377695 0)
			(layer "F.Fab")
			(hide yes)
			(effects
				(font
					(size 1 1)
					(thickness 0.15)
				)
			)
		)
		(property "Public" ""
			(at 39.370305 327.377695 0)
			(layer "F.Fab")
			(hide yes)
			(effects
				(font
					(size 1 1)
					(thickness 0.15)
				)
			)
		)
		(property "Size" "2.0x1.6"
			(at 39.370305 327.377695 0)
			(layer "F.Fab")
			(hide yes)
			(effects
				(font
					(size 1 1)
					(thickness 0.15)
				)
			)
		)
		(property "Val" "1.5u/2.8A"
			(at 39.370305 327.377695 0)
			(layer "F.Fab")
			(hide yes)
			(effects
				(font
					(size 1 1)
					(thickness 0.15)
				)
			)
		)
		(sheetname "/Supply/")
		(sheetfile "supply.kicad_sch")
		(attr smd)
		(fp_line
			(start -0.301 0.9)
			(end 0.299 0.9)
			(stroke
				(width 0.15)
				(type solid)
			)
			(layer "F.SilkS")
		)
		(fp_line
			(start -0.3 -0.9)
			(end 0.298 -0.9)
			(stroke
				(width 0.15)
				(type solid)
			)
			(layer "F.SilkS")
		)
		(fp_rect
			(start -1.75 -1.05)
			(end 1.75 1.05)
			(stroke
				(width 0.05)
				(type solid)
			)
			(fill no)
			(layer "F.CrtYd")
		)
		(fp_rect
			(start -0.951 -0.882)
			(end 0.949 0.875)
			(stroke
				(width 0.15)
				(type solid)
			)
			(fill no)
			(layer "F.Fab")
		)
		(fp_text user "${REFERENCE}"
			(at -1.9 3.1 270)
			(layer "F.Fab")
			(effects
				(font
					(size 0.7 0.7)
					(thickness 0.15)
				)
				(justify left bottom)
			)
		)
		(fp_text user "Author: Antmicro"
			(at -1.9 4.4 270)
			(layer "F.Fab")
			(effects
				(font
					(size 0.7 0.7)
					(thickness 0.15)
				)
				(justify left bottom)
			)
		)
		(fp_text user "License: Apache-2.0"
			(at -1.9 5.75 270)
			(layer "F.Fab")
			(effects
				(font
					(size 0.7 0.7)
					(thickness 0.15)
				)
				(justify left bottom)
			)
		)
		(pad "1" smd roundrect
			(at -1.1 -0.001 270)
			(size 1 1.8)
			(layers "F.Cu" "F.Mask" "F.Paste")
			(roundrect_rratio 0.15)
			(net 184 "Net-(U7-SW4)")
			(pintype "passive")
		)
		(pad "2" smd roundrect
			(at 1.1 -0.001 270)
			(size 1 1.8)
			(layers "F.Cu" "F.Mask" "F.Paste")
			(roundrect_rratio 0.15)
			(net 409 "/Supply/SENSE4_P")
			(pintype "passive")
		)
	)
)
